# T6G (Grand Teton) — schematic netlist excerpt (pin names and nets, part order shuffled) for the footprints in the layout excerpt that follows; sources: Cadence DE-HDL packaged netlist, KiCad conversion of 04192023_DAF0TMB3IC0_F0TG_MB_C_brd_V02_OCP.brd

R592  Q_RES  10K 1% CHIP  pkg 0402LF  page 183 : A = FM_9ZXL045_P1_2_OE_N ; B = GND
R8380  Q_RES  1K 1% CHIP  pkg 0402LF  page 224 : A = P3V3_AUX ; B = PWRGD_PVDD11_S3_P1_R

(kicad_pcb
	(version 20260206)
	(generator "pcbnew")
	(generator_version "10.0")
	(general
		(thickness 1.6)
		(legacy_teardrops no)
	)
	(paper "A4")
	(title_block
		(title "04192023_DAF0TMB3IC0_F0TG_MB_C_brd_V02_OCP.brd")
		(comment 1 "Grand Teton / footprints 4320-4321 of 8354")
	)
	(layers
		(0 "F.Cu" signal "TOP")
		(4 "In1.Cu" signal "GND")
		(6 "In2.Cu" signal "IN1")
		(8 "In3.Cu" signal "GND1")
		(10 "In4.Cu" signal "IN2")
		(12 "In5.Cu" signal "GND2")
		(14 "In6.Cu" signal "IN3")
		(16 "In7.Cu" signal "GND3")
		(18 "In8.Cu" signal "VCC")
		(20 "In9.Cu" signal "VCC1")
		(22 "In10.Cu" signal "GND4")
		(24 "In11.Cu" signal "IN4")
		(26 "In12.Cu" signal "GND5")
		(28 "In13.Cu" signal "IN5")
		(30 "In14.Cu" signal "GND6")
		(32 "In15.Cu" signal "IN6")
		(34 "In16.Cu" signal "GND7")
		(2 "B.Cu" signal "BOTTOM")
		(9 "F.Adhes" user "F.Adhesive")
		(11 "B.Adhes" user "B.Adhesive")
		(13 "F.Paste" user "Package Geometry/Pastemask Top")
		(15 "B.Paste" user "Package Geometry/Pastemask Bottom")
		(5 "F.SilkS" user "Ref Des/Silkscreen Top")
		(7 "B.SilkS" user "Ref Des/Silkscreen Bottom")
		(1 "F.Mask" user "Board Geometry/Soldermask Top")
		(3 "B.Mask" user "Board Geometry/Soldermask Bottom")
		(17 "Dwgs.User" user "User.Drawings")
		(19 "Cmts.User" user "User.Comments")
		(21 "Eco1.User" user "User.Eco1")
		(23 "Eco2.User" user "User.Eco2")
		(25 "Edge.Cuts" user "Board Geometry/Outline")
		(27 "Margin" user)
		(31 "F.CrtYd" user "Package Geometry/Place Bound Top")
		(29 "B.CrtYd" user "Package Geometry/Place Bound Bottom")
		(35 "F.Fab" user "Ref Des/Assembly Top")
		(33 "B.Fab" user "Ref Des/Assembly Bottom")
	)
	(footprint ""
		(layer "F.Cu")
		(at 157.677358 -352.229928)
		(property "Reference" "R8380"
			(at 0 0 0)
			(layer "F.SilkS")
			(hide yes)
			(effects
				(font
					(size 1.27 1.27)
				)
			)
		)
		(property "Value" ""
			(at 0 0 0)
			(layer "F.Fab")
			(effects
				(font
					(size 1.27 1.27)
				)
			)
		)
		(duplicate_pad_numbers_are_jumpers no)
		(fp_line
			(start -0.7874 -0.4064)
			(end 0.7874 -0.4064)
			(stroke
				(width 0.1524)
				(type default)
			)
			(layer "F.SilkS")
		)
		(fp_line
			(start -0.7874 0.4064)
			(end -0.7874 -0.4064)
			(stroke
				(width 0.1524)
				(type default)
			)
			(layer "F.SilkS")
		)
		(fp_line
			(start 0.7874 -0.4064)
			(end 0.7874 0.4064)
			(stroke
				(width 0.1524)
				(type default)
			)
			(layer "F.SilkS")
		)
		(fp_line
			(start 0.7874 0.4064)
			(end -0.7874 0.4064)
			(stroke
				(width 0.1524)
				(type default)
			)
			(layer "F.SilkS")
		)
		(fp_line
			(start -0.67945 -0.305054)
			(end -0.12065 -0.305054)
			(stroke
				(width 0.1)
				(type default)
			)
			(layer "F.Fab")
		)
		(fp_line
			(start -0.67945 0.3048)
			(end -0.67945 -0.305054)
			(stroke
				(width 0.1)
				(type default)
			)
			(layer "F.Fab")
		)
		(fp_line
			(start -0.12065 -0.305054)
			(end -0.12065 -0.2794)
			(stroke
				(width 0.1)
				(type default)
			)
			(layer "F.Fab")
		)
		(fp_line
			(start -0.12065 -0.2794)
			(end 0.12065 -0.2794)
			(stroke
				(width 0.1)
				(type default)
			)
			(layer "F.Fab")
		)
		(fp_line
			(start -0.12065 0.2794)
			(end -0.12065 0.3048)
			(stroke
				(width 0.1)
				(type default)
			)
			(layer "F.Fab")
		)
		(fp_line
			(start -0.12065 0.3048)
			(end -0.67945 0.3048)
			(stroke
				(width 0.1)
				(type default)
			)
			(layer "F.Fab")
		)
		(fp_line
			(start 0.120396 0.2794)
			(end -0.12065 0.2794)
			(stroke
				(width 0.1)
				(type default)
			)
			(layer "F.Fab")
		)
		(fp_line
			(start 0.120396 0.3048)
			(end 0.120396 0.2794)
			(stroke
				(width 0.1)
				(type default)
			)
			(layer "F.Fab")
		)
		(fp_line
			(start 0.12065 -0.3048)
			(end 0.67945 -0.3048)
			(stroke
				(width 0.1)
				(type default)
			)
			(layer "F.Fab")
		)
		(fp_line
			(start 0.12065 -0.2794)
			(end 0.12065 -0.3048)
			(stroke
				(width 0.1)
				(type default)
			)
			(layer "F.Fab")
		)
		(fp_line
			(start 0.67945 -0.3048)
			(end 0.67945 0.3048)
			(stroke
				(width 0.1)
				(type default)
			)
			(layer "F.Fab")
		)
		(fp_line
			(start 0.67945 0.3048)
			(end 0.120396 0.3048)
			(stroke
				(width 0.1)
				(type default)
			)
			(layer "F.Fab")
		)
		(pad "1" smd circle
			(at -0.40005 0)
			(size 0 0)
			(layers "F.Cu" "F.Mask" "F.Paste")
			(net "P3V3_AUX")
		)
		(pad "2" smd circle
			(at 0.40005 0)
			(size 0 0)
			(layers "F.Cu" "F.Mask" "F.Paste")
			(net "PWRGD_PVDD11_S3_P1_R")
		)
	)
	(footprint ""
		(layer "F.Cu")
		(at 111.76 -406.4508)
		(property "Reference" "R592"
			(at 0 0 0)
			(layer "F.SilkS")
			(hide yes)
			(effects
				(font
					(size 1.27 1.27)
				)
			)
		)
		(property "Value" ""
			(at 0 0 0)
			(layer "F.Fab")
			(effects
				(font
					(size 1.27 1.27)
				)
			)
		)
		(duplicate_pad_numbers_are_jumpers no)
		(fp_line
			(start -0.7874 -0.4064)
			(end 0.7874 -0.4064)
			(stroke
				(width 0.1524)
				(type default)
			)
			(layer "F.SilkS")
		)
		(fp_line
			(start -0.7874 0.4064)
			(end -0.7874 -0.4064)
			(stroke
				(width 0.1524)
				(type default)
			)
			(layer "F.SilkS")
		)
		(fp_line
			(start 0.7874 -0.4064)
			(end 0.7874 0.4064)
			(stroke
				(width 0.1524)
				(type default)
			)
			(layer "F.SilkS")
		)
		(fp_line
			(start 0.7874 0.4064)
			(end -0.7874 0.4064)
			(stroke
				(width 0.1524)
				(type default)
			)
			(layer "F.SilkS")
		)
		(fp_line
			(start -0.67945 -0.305054)
			(end -0.12065 -0.305054)
			(stroke
				(width 0.1)
				(type default)
			)
			(layer "F.Fab")
		)
		(fp_line
			(start -0.67945 0.3048)
			(end -0.67945 -0.305054)
			(stroke
				(width 0.1)
				(type default)
			)
			(layer "F.Fab")
		)
		(fp_line
			(start -0.12065 -0.305054)
			(end -0.12065 -0.2794)
			(stroke
				(width 0.1)
				(type default)
			)
			(layer "F.Fab")
		)
		(fp_line
			(start -0.12065 -0.2794)
			(end 0.12065 -0.2794)
			(stroke
				(width 0.1)
				(type default)
			)
			(layer "F.Fab")
		)
		(fp_line
			(start -0.12065 0.2794)
			(end -0.12065 0.3048)
			(stroke
				(width 0.1)
				(type default)
			)
			(layer "F.Fab")
		)
		(fp_line
			(start -0.12065 0.3048)
			(end -0.67945 0.3048)
			(stroke
				(width 0.1)
				(type default)
			)
			(layer "F.Fab")
		)
		(fp_line
			(start 0.120396 0.2794)
			(end -0.12065 0.2794)
			(stroke
				(width 0.1)
				(type default)
			)
			(layer "F.Fab")
		)
		(fp_line
			(start 0.120396 0.3048)
			(end 0.120396 0.2794)
			(stroke
				(width 0.1)
				(type default)
			)
			(layer "F.Fab")
		)
		(fp_line
			(start 0.12065 -0.3048)
			(end 0.67945 -0.3048)
			(stroke
				(width 0.1)
				(type default)
			)
			(layer "F.Fab")
		)
		(fp_line
			(start 0.12065 -0.2794)
			(end 0.12065 -0.3048)
			(stroke
				(width 0.1)
				(type default)
			)
			(layer "F.Fab")
		)
		(fp_line
			(start 0.67945 -0.3048)
			(end 0.67945 0.3048)
			(stroke
				(width 0.1)
				(type default)
			)
			(layer "F.Fab")
		)
		(fp_line
			(start 0.67945 0.3048)
			(end 0.120396 0.3048)
			(stroke
				(width 0.1)
				(type default)
			)
			(layer "F.Fab")
		)
		(pad "1" smd circle
			(at -0.40005 0)
			(size 0 0)
			(layers "F.Cu" "F.Mask" "F.Paste")
			(net "FM_9ZXL045_P1_2_OE_N")
		)
		(pad "2" smd circle
			(at 0.40005 0)
			(size 0 0)
			(layers "F.Cu" "F.Mask" "F.Paste")
			(net "GND")
		)
	)
)
